(kicad_pcb
	(version 20260206)
	(generator "pcbnew")
	(generator_version "10.0")
	(general
		(thickness 1.6)
		(legacy_teardrops no)
	)
	(paper "A4")
	(title_block
		(title "01162023_DA0F0TEBIF0_F0T_Expander_BD_F_brd_V02_OCP.brd")
		(comment 1 "Grand Teton / footprints 2541-2546 of 9728")
	)
	(layers
		(0 "F.Cu" signal "TOP")
		(4 "In1.Cu" signal "GND")
		(6 "In2.Cu" signal "VCC")
		(8 "In3.Cu" signal "VCC1")
		(10 "In4.Cu" signal "GND1")
		(12 "In5.Cu" signal "IN1")
		(14 "In6.Cu" signal "GND2")
		(16 "In7.Cu" signal "IN2")
		(18 "In8.Cu" signal "GND3")
		(20 "In9.Cu" signal "IN3")
		(22 "In10.Cu" signal "GND4")
		(24 "In11.Cu" signal "IN4")
		(26 "In12.Cu" signal "GND5")
		(28 "In13.Cu" signal "IN5")
		(30 "In14.Cu" signal "GND6")
		(32 "In15.Cu" signal "IN6")
		(34 "In16.Cu" signal "GND7")
		(2 "B.Cu" signal "BOTTOM")
		(9 "F.Adhes" user "F.Adhesive")
		(11 "B.Adhes" user "B.Adhesive")
		(13 "F.Paste" user "Package Geometry/Pastemask Top")
		(15 "B.Paste" user "Package Geometry/Pastemask Bottom")
		(5 "F.SilkS" user "Ref Des/Silkscreen Top")
		(7 "B.SilkS" user "Ref Des/Silkscreen Bottom")
		(1 "F.Mask" user "Board Geometry/Soldermask Top")
		(3 "B.Mask" user "Board Geometry/Soldermask Bottom")
		(17 "Dwgs.User" user "User.Drawings")
		(19 "Cmts.User" user "User.Comments")
		(21 "Eco1.User" user "User.Eco1")
		(23 "Eco2.User" user "User.Eco2")
		(25 "Edge.Cuts" user "Board Geometry/Outline")
		(27 "Margin" user)
		(31 "F.CrtYd" user "Package Geometry/Place Bound Top")
		(29 "B.CrtYd" user "Package Geometry/Place Bound Bottom")
		(35 "F.Fab" user "Ref Des/Assembly Top")
		(33 "B.Fab" user "Ref Des/Assembly Bottom")
	)
	(footprint ""
		(layer "F.Cu")
		(at 284.467046 -57.332626)
		(property "Reference" "R6832"
			(at 0 0 0)
			(layer "F.SilkS")
			(hide yes)
			(effects
				(font
					(size 1.27 1.27)
				)
			)
		)
		(property "Value" ""
			(at 0 0 0)
			(layer "F.Fab")
			(effects
				(font
					(size 1.27 1.27)
				)
			)
		)
		(duplicate_pad_numbers_are_jumpers no)
		(fp_line
			(start -0.7874 -0.4064)
			(end 0.7874 -0.4064)
			(stroke
				(width 0.1524)
				(type default)
			)
			(layer "F.SilkS")
		)
		(fp_line
			(start -0.7874 0.4064)
			(end -0.7874 -0.4064)
			(stroke
				(width 0.1524)
				(type default)
			)
			(layer "F.SilkS")
		)
		(fp_line
			(start 0.7874 -0.4064)
			(end 0.7874 0.4064)
			(stroke
				(width 0.1524)
				(type default)
			)
			(layer "F.SilkS")
		)
		(fp_line
			(start 0.7874 0.4064)
			(end -0.7874 0.4064)
			(stroke
				(width 0.1524)
				(type default)
			)
			(layer "F.SilkS")
		)
		(fp_line
			(start -0.67945 -0.305054)
			(end -0.12065 -0.305054)
			(stroke
				(width 0.1)
				(type default)
			)
			(layer "F.Fab")
		)
		(fp_line
			(start -0.67945 0.3048)
			(end -0.67945 -0.305054)
			(stroke
				(width 0.1)
				(type default)
			)
			(layer "F.Fab")
		)
		(fp_line
			(start -0.12065 -0.305054)
			(end -0.12065 -0.2794)
			(stroke
				(width 0.1)
				(type default)
			)
			(layer "F.Fab")
		)
		(fp_line
			(start -0.12065 -0.2794)
			(end 0.12065 -0.2794)
			(stroke
				(width 0.1)
				(type default)
			)
			(layer "F.Fab")
		)
		(fp_line
			(start -0.12065 0.2794)
			(end -0.12065 0.3048)
			(stroke
				(width 0.1)
				(type default)
			)
			(layer "F.Fab")
		)
		(fp_line
			(start -0.12065 0.3048)
			(end -0.67945 0.3048)
			(stroke
				(width 0.1)
				(type default)
			)
			(layer "F.Fab")
		)
		(fp_line
			(start 0.120396 0.2794)
			(end -0.12065 0.2794)
			(stroke
				(width 0.1)
				(type default)
			)
			(layer "F.Fab")
		)
		(fp_line
			(start 0.120396 0.3048)
			(end 0.120396 0.2794)
			(stroke
				(width 0.1)
				(type default)
			)
			(layer "F.Fab")
		)
		(fp_line
			(start 0.12065 -0.3048)
			(end 0.67945 -0.3048)
			(stroke
				(width 0.1)
				(type default)
			)
			(layer "F.Fab")
		)
		(fp_line
			(start 0.12065 -0.2794)
			(end 0.12065 -0.3048)
			(stroke
				(width 0.1)
				(type default)
			)
			(layer "F.Fab")
		)
		(fp_line
			(start 0.67945 -0.3048)
			(end 0.67945 0.3048)
			(stroke
				(width 0.1)
				(type default)
			)
			(layer "F.Fab")
		)
		(fp_line
			(start 0.67945 0.3048)
			(end 0.120396 0.3048)
			(stroke
				(width 0.1)
				(type default)
			)
			(layer "F.Fab")
		)
		(pad "1" smd circle
			(at -0.40005 0)
			(size 0 0)
			(layers "F.Cu" "F.Mask" "F.Paste")
			(net "SSD9_PWR_EN_R")
		)
		(pad "2" smd circle
			(at 0.40005 0)
			(size 0 0)
			(layers "F.Cu" "F.Mask" "F.Paste")
			(net "GND")
		)
	)
	(footprint ""
		(layer "F.Cu")
		(at 410.612082 -193.802508 -90)
		(property "Reference" "R6429"
			(at 0 0 270)
			(layer "F.SilkS")
			(hide yes)
			(effects
				(font
					(size 1.27 1.27)
				)
			)
		)
		(property "Value" ""
			(at 0 0 270)
			(layer "F.Fab")
			(effects
				(font
					(size 1.27 1.27)
				)
			)
		)
		(duplicate_pad_numbers_are_jumpers no)
		(fp_line
			(start -0.7874 0.4064)
			(end -0.7874 -0.4064)
			(stroke
				(width 0.1524)
				(type default)
			)
			(layer "F.SilkS")
		)
		(fp_line
			(start 0.7874 0.4064)
			(end -0.7874 0.4064)
			(stroke
				(width 0.1524)
				(type default)
			)
			(layer "F.SilkS")
		)
		(fp_line
			(start -0.7874 -0.4064)
			(end 0.7874 -0.4064)
			(stroke
				(width 0.1524)
				(type default)
			)
			(layer "F.SilkS")
		)
		(fp_line
			(start 0.7874 -0.4064)
			(end 0.7874 0.4064)
			(stroke
				(width 0.1524)
				(type default)
			)
			(layer "F.SilkS")
		)
		(fp_line
			(start -0.67945 0.3048)
			(end -0.67945 -0.305054)
			(stroke
				(width 0.1)
				(type default)
			)
			(layer "F.Fab")
		)
		(fp_line
			(start -0.12065 0.3048)
			(end -0.67945 0.3048)
			(stroke
				(width 0.1)
				(type default)
			)
			(layer "F.Fab")
		)
		(fp_line
			(start 0.120396 0.3048)
			(end 0.120396 0.2794)
			(stroke
				(width 0.1)
				(type default)
			)
			(layer "F.Fab")
		)
		(fp_line
			(start 0.67945 0.3048)
			(end 0.120396 0.3048)
			(stroke
				(width 0.1)
				(type default)
			)
			(layer "F.Fab")
		)
		(fp_line
			(start -0.12065 0.2794)
			(end -0.12065 0.3048)
			(stroke
				(width 0.1)
				(type default)
			)
			(layer "F.Fab")
		)
		(fp_line
			(start 0.120396 0.2794)
			(end -0.12065 0.2794)
			(stroke
				(width 0.1)
				(type default)
			)
			(layer "F.Fab")
		)
		(fp_line
			(start -0.12065 -0.2794)
			(end 0.12065 -0.2794)
			(stroke
				(width 0.1)
				(type default)
			)
			(layer "F.Fab")
		)
		(fp_line
			(start 0.12065 -0.2794)
			(end 0.12065 -0.3048)
			(stroke
				(width 0.1)
				(type default)
			)
			(layer "F.Fab")
		)
		(fp_line
			(start 0.12065 -0.3048)
			(end 0.67945 -0.3048)
			(stroke
				(width 0.1)
				(type default)
			)
			(layer "F.Fab")
		)
		(fp_line
			(start 0.67945 -0.3048)
			(end 0.67945 0.3048)
			(stroke
				(width 0.1)
				(type default)
			)
			(layer "F.Fab")
		)
		(fp_line
			(start -0.67945 -0.305054)
			(end -0.12065 -0.305054)
			(stroke
				(width 0.1)
				(type default)
			)
			(layer "F.Fab")
		)
		(fp_line
			(start -0.12065 -0.305054)
			(end -0.12065 -0.2794)
			(stroke
				(width 0.1)
				(type default)
			)
			(layer "F.Fab")
		)
		(pad "1" smd circle
			(at -0.40005 0 270)
			(size 0 0)
			(layers "F.Cu" "F.Mask" "F.Paste")
			(net "FPGA_PEX0_MODE_SEL1_ISO")
		)
		(pad "2" smd circle
			(at 0.40005 0 270)
			(size 0 0)
			(layers "F.Cu" "F.Mask" "F.Paste")
			(net "PEX0_MODE_SEL1")
		)
	)
	(footprint ""
		(layer "F.Cu")
		(at 249.733562 -212.638386 180)
		(property "Reference" "R4434"
			(at 0 0 180)
			(layer "F.SilkS")
			(hide yes)
			(effects
				(font
					(size 1.27 1.27)
				)
			)
		)
		(property "Value" ""
			(at 0 0 180)
			(layer "F.Fab")
			(effects
				(font
					(size 1.27 1.27)
				)
			)
		)
		(duplicate_pad_numbers_are_jumpers no)
		(fp_line
			(start 0.7874 0.4064)
			(end -0.7874 0.4064)
			(stroke
				(width 0.1524)
				(type default)
			)
			(layer "F.SilkS")
		)
		(fp_line
			(start 0.7874 -0.4064)
			(end 0.7874 0.4064)
			(stroke
				(width 0.1524)
				(type default)
			)
			(layer "F.SilkS")
		)
		(fp_line
			(start -0.7874 0.4064)
			(end -0.7874 -0.4064)
			(stroke
				(width 0.1524)
				(type default)
			)
			(layer "F.SilkS")
		)
		(fp_line
			(start -0.7874 -0.4064)
			(end 0.7874 -0.4064)
			(stroke
				(width 0.1524)
				(type default)
			)
			(layer "F.SilkS")
		)
		(fp_line
			(start 0.67945 0.3048)
			(end 0.120396 0.3048)
			(stroke
				(width 0.1)
				(type default)
			)
			(layer "F.Fab")
		)
		(fp_line
			(start 0.67945 -0.3048)
			(end 0.67945 0.3048)
			(stroke
				(width 0.1)
				(type default)
			)
			(layer "F.Fab")
		)
		(fp_line
			(start 0.12065 -0.2794)
			(end 0.12065 -0.3048)
			(stroke
				(width 0.1)
				(type default)
			)
			(layer "F.Fab")
		)
		(fp_line
			(start 0.12065 -0.3048)
			(end 0.67945 -0.3048)
			(stroke
				(width 0.1)
				(type default)
			)
			(layer "F.Fab")
		)
		(fp_line
			(start 0.120396 0.3048)
			(end 0.120396 0.2794)
			(stroke
				(width 0.1)
				(type default)
			)
			(layer "F.Fab")
		)
		(fp_line
			(start 0.120396 0.2794)
			(end -0.12065 0.2794)
			(stroke
				(width 0.1)
				(type default)
			)
			(layer "F.Fab")
		)
		(fp_line
			(start -0.12065 0.3048)
			(end -0.67945 0.3048)
			(stroke
				(width 0.1)
				(type default)
			)
			(layer "F.Fab")
		)
		(fp_line
			(start -0.12065 0.2794)
			(end -0.12065 0.3048)
			(stroke
				(width 0.1)
				(type default)
			)
			(layer "F.Fab")
		)
		(fp_line
			(start -0.12065 -0.2794)
			(end 0.12065 -0.2794)
			(stroke
				(width 0.1)
				(type default)
			)
			(layer "F.Fab")
		)
		(fp_line
			(start -0.12065 -0.305054)
			(end -0.12065 -0.2794)
			(stroke
				(width 0.1)
				(type default)
			)
			(layer "F.Fab")
		)
		(fp_line
			(start -0.67945 0.3048)
			(end -0.67945 -0.305054)
			(stroke
				(width 0.1)
				(type default)
			)
			(layer "F.Fab")
		)
		(fp_line
			(start -0.67945 -0.305054)
			(end -0.12065 -0.305054)
			(stroke
				(width 0.1)
				(type default)
			)
			(layer "F.Fab")
		)
		(pad "1" smd circle
			(at -0.40005 0 180)
			(size 0 0)
			(layers "F.Cu" "F.Mask" "F.Paste")
			(net "P1V2_AUX_ADJ")
		)
		(pad "2" smd circle
			(at 0.40005 0 180)
			(size 0 0)
			(layers "F.Cu" "F.Mask" "F.Paste")
			(net "GND")
		)
	)
	(footprint ""
		(layer "F.Cu")
		(at 213.896194 -47.20082 90)
		(property "Reference" "C319"
			(at 0 0 90)
			(layer "F.SilkS")
			(hide yes)
			(effects
				(font
					(size 1.27 1.27)
				)
			)
		)
		(property "Value" ""
			(at 0 0 90)
			(layer "F.Fab")
			(effects
				(font
					(size 1.27 1.27)
				)
			)
		)
		(duplicate_pad_numbers_are_jumpers no)
		(fp_line
			(start 0.7874 -0.4064)
			(end 0.7874 0.4064)
			(stroke
				(width 0.1524)
				(type default)
			)
			(layer "F.SilkS")
		)
		(fp_line
			(start -0.7874 -0.4064)
			(end 0.7874 -0.4064)
			(stroke
				(width 0.1524)
				(type default)
			)
			(layer "F.SilkS")
		)
		(fp_line
			(start 0.7874 0.4064)
			(end -0.7874 0.4064)
			(stroke
				(width 0.1524)
				(type default)
			)
			(layer "F.SilkS")
		)
		(fp_line
			(start -0.7874 0.4064)
			(end -0.7874 -0.4064)
			(stroke
				(width 0.1524)
				(type default)
			)
			(layer "F.SilkS")
		)
		(fp_line
			(start -0.12065 -0.305054)
			(end -0.12065 -0.2794)
			(stroke
				(width 0.1)
				(type default)
			)
			(layer "F.Fab")
		)
		(fp_line
			(start -0.67945 -0.305054)
			(end -0.12065 -0.305054)
			(stroke
				(width 0.1)
				(type default)
			)
			(layer "F.Fab")
		)
		(fp_line
			(start 0.67945 -0.3048)
			(end 0.67945 0.3048)
			(stroke
				(width 0.1)
				(type default)
			)
			(layer "F.Fab")
		)
		(fp_line
			(start 0.12065 -0.3048)
			(end 0.67945 -0.3048)
			(stroke
				(width 0.1)
				(type default)
			)
			(layer "F.Fab")
		)
		(fp_line
			(start 0.12065 -0.2794)
			(end 0.12065 -0.3048)
			(stroke
				(width 0.1)
				(type default)
			)
			(layer "F.Fab")
		)
		(fp_line
			(start -0.12065 -0.2794)
			(end 0.12065 -0.2794)
			(stroke
				(width 0.1)
				(type default)
			)
			(layer "F.Fab")
		)
		(fp_line
			(start 0.120396 0.2794)
			(end -0.12065 0.2794)
			(stroke
				(width 0.1)
				(type default)
			)
			(layer "F.Fab")
		)
		(fp_line
			(start -0.12065 0.2794)
			(end -0.12065 0.3048)
			(stroke
				(width 0.1)
				(type default)
			)
			(layer "F.Fab")
		)
		(fp_line
			(start 0.67945 0.3048)
			(end 0.120396 0.3048)
			(stroke
				(width 0.1)
				(type default)
			)
			(layer "F.Fab")
		)
		(fp_line
			(start 0.120396 0.3048)
			(end 0.120396 0.2794)
			(stroke
				(width 0.1)
				(type default)
			)
			(layer "F.Fab")
		)
		(fp_line
			(start -0.12065 0.3048)
			(end -0.67945 0.3048)
			(stroke
				(width 0.1)
				(type default)
			)
			(layer "F.Fab")
		)
		(fp_line
			(start -0.67945 0.3048)
			(end -0.67945 -0.305054)
			(stroke
				(width 0.1)
				(type default)
			)
			(layer "F.Fab")
		)
		(pad "1" smd circle
			(at -0.40005 0 90)
			(size 0 0)
			(layers "F.Cu" "F.Mask" "F.Paste")
			(net "P12V_SSD7_R")
		)
		(pad "2" smd circle
			(at 0.40005 0 90)
			(size 0 0)
			(layers "F.Cu" "F.Mask" "F.Paste")
			(net "GND")
		)
	)
	(footprint ""
		(layer "F.Cu")
		(at 168.343834 -49.95291 180)
		(property "Reference" "R566"
			(at 0 0 180)
			(layer "F.SilkS")
			(hide yes)
			(effects
				(font
					(size 1.27 1.27)
				)
			)
		)
		(property "Value" ""
			(at 0 0 180)
			(layer "F.Fab")
			(effects
				(font
					(size 1.27 1.27)
				)
			)
		)
		(duplicate_pad_numbers_are_jumpers no)
		(fp_line
			(start 0.7874 0.4064)
			(end -0.7874 0.4064)
			(stroke
				(width 0.1524)
				(type default)
			)
			(layer "F.SilkS")
		)
		(fp_line
			(start 0.7874 -0.4064)
			(end 0.7874 0.4064)
			(stroke
				(width 0.1524)
				(type default)
			)
			(layer "F.SilkS")
		)
		(fp_line
			(start -0.7874 0.4064)
			(end -0.7874 -0.4064)
			(stroke
				(width 0.1524)
				(type default)
			)
			(layer "F.SilkS")
		)
		(fp_line
			(start -0.7874 -0.4064)
			(end 0.7874 -0.4064)
			(stroke
				(width 0.1524)
				(type default)
			)
			(layer "F.SilkS")
		)
		(fp_line
			(start 0.67945 0.3048)
			(end 0.120396 0.3048)
			(stroke
				(width 0.1)
				(type default)
			)
			(layer "F.Fab")
		)
		(fp_line
			(start 0.67945 -0.3048)
			(end 0.67945 0.3048)
			(stroke
				(width 0.1)
				(type default)
			)
			(layer "F.Fab")
		)
		(fp_line
			(start 0.12065 -0.2794)
			(end 0.12065 -0.3048)
			(stroke
				(width 0.1)
				(type default)
			)
			(layer "F.Fab")
		)
		(fp_line
			(start 0.12065 -0.3048)
			(end 0.67945 -0.3048)
			(stroke
				(width 0.1)
				(type default)
			)
			(layer "F.Fab")
		)
		(fp_line
			(start 0.120396 0.3048)
			(end 0.120396 0.2794)
			(stroke
				(width 0.1)
				(type default)
			)
			(layer "F.Fab")
		)
		(fp_line
			(start 0.120396 0.2794)
			(end -0.12065 0.2794)
			(stroke
				(width 0.1)
				(type default)
			)
			(layer "F.Fab")
		)
		(fp_line
			(start -0.12065 0.3048)
			(end -0.67945 0.3048)
			(stroke
				(width 0.1)
				(type default)
			)
			(layer "F.Fab")
		)
		(fp_line
			(start -0.12065 0.2794)
			(end -0.12065 0.3048)
			(stroke
				(width 0.1)
				(type default)
			)
			(layer "F.Fab")
		)
		(fp_line
			(start -0.12065 -0.2794)
			(end 0.12065 -0.2794)
			(stroke
				(width 0.1)
				(type default)
			)
			(layer "F.Fab")
		)
		(fp_line
			(start -0.12065 -0.305054)
			(end -0.12065 -0.2794)
			(stroke
				(width 0.1)
				(type default)
			)
			(layer "F.Fab")
		)
		(fp_line
			(start -0.67945 0.3048)
			(end -0.67945 -0.305054)
			(stroke
				(width 0.1)
				(type default)
			)
			(layer "F.Fab")
		)
		(fp_line
			(start -0.67945 -0.305054)
			(end -0.12065 -0.305054)
			(stroke
				(width 0.1)
				(type default)
			)
			(layer "F.Fab")
		)
		(pad "1" smd circle
			(at -0.40005 0 180)
			(size 0 0)
			(layers "F.Cu" "F.Mask" "F.Paste")
			(net "SMB_BIC_I2C6_MUX_SSD_0_7_ADC_R_SCL")
		)
		(pad "2" smd circle
			(at 0.40005 0 180)
			(size 0 0)
			(layers "F.Cu" "F.Mask" "F.Paste")
			(net "SMB_SSD5_ADC_SCL")
		)
	)
	(footprint ""
		(layer "F.Cu")
		(at 231.460294 -180.28158)
		(property "Reference" "Q56"
			(at -3.977894 0.55245 0)
			(unlocked yes)
			(layer "F.SilkS")
			(effects
				(font
					(size 0.7874 0.5842)
					(thickness 0.1524)
				)
				(justify left)
			)
		)
		(property "Value" ""
			(at 0 0 0)
			(layer "F.Fab")
			(effects
				(font
					(size 1.27 1.27)
				)
			)
		)
		(duplicate_pad_numbers_are_jumpers no)
		(fp_line
			(start -1.584198 -1.53416)
			(end 1.584198 -1.53416)
			(stroke
				(width 0.1524)
				(type default)
			)
			(layer "F.SilkS")
		)
		(fp_line
			(start -1.584198 1.53416)
			(end -1.584198 -1.53416)
			(stroke
				(width 0.1524)
				(type default)
			)
			(layer "F.SilkS")
		)
		(fp_line
			(start 1.584198 -1.53416)
			(end 1.584198 1.53416)
			(stroke
				(width 0.1524)
				(type default)
			)
			(layer "F.SilkS")
		)
		(fp_line
			(start 1.584198 1.53416)
			(end -1.584198 1.53416)
			(stroke
				(width 0.1524)
				(type default)
			)
			(layer "F.SilkS")
		)
		(fp_line
			(start -0.700024 -1.500124)
			(end 0.700024 -1.500124)
			(stroke
				(width 0.1)
				(type default)
			)
			(layer "F.Fab")
		)
		(fp_line
			(start -0.700024 1.500124)
			(end -0.700024 -1.500124)
			(stroke
				(width 0.1)
				(type default)
			)
			(layer "F.Fab")
		)
		(fp_line
			(start 0.700024 -1.500124)
			(end 0.700024 1.500124)
			(stroke
				(width 0.1)
				(type default)
			)
			(layer "F.Fab")
		)
		(fp_line
			(start 0.700024 1.500124)
			(end -0.700024 1.500124)
			(stroke
				(width 0.1)
				(type default)
			)
			(layer "F.Fab")
		)
		(pad "B" smd rect
			(at -0.999998 -0.94996 90)
			(size 0.8128 0.9144)
			(layers "F.Cu" "F.Mask" "F.Paste")
			(net "RST_BJT_Q15_C")
		)
		(pad "C" smd rect
			(at 0.999998 0 90)
			(size 0.8128 0.9144)
			(layers "F.Cu" "F.Mask" "F.Paste")
			(net "RST_BIC_EXTRST_R_N")
		)
		(pad "E" smd rect
			(at -0.999998 0.94996 90)
			(size 0.8128 0.9144)
			(layers "F.Cu" "F.Mask" "F.Paste")
			(net "GND")
		)
	)
)
